FILE_TYPE = MULTI_PHYS_TABLE;
PART 'SCONN24_H46321001'
{===============================================================================================================================================================================================================}
:PACK_TYPE | MATERIAL | PART_NUMBER     = EnvComp | PART_NUMBER  | JEDEC_TYPE             | DESCRIPTION                         | CLASS | COMPONENT_TYPE | HEIGHT     | LPID   | SPEED_URL | Status |RPL| AML | Bus_Unit | Days ;
{===============================================================================================================================================================================================================}
'SM'       | 'SCONN'  | 'H46321-001'(!) = ''      | 'H46321-001' | 'SCONN24_H46321001'    |'CONN_HDR,2X12,PLG,VT,1.00MM,SMT,BK' | 'IC'  | 'SMTCONN'      | '0.197 IN' |'3521'  | 'http://speed.intel.com:8081/speed/module/pdm/item/pdm_item_detail_direct.asp?item_cde=H46321-001&item_rev=01&url_param=unused' | '' | '' | '' | '' | '' 
'SM'       | 'EMPTY'  | 'H46321-001'(!) = ''      | 'H46321-001' | 'SCONN24_H46321001'    |'CONN_HDR,2X12,PLG,VT,1.00MM,SMT,BK' | 'IO'  | 'SMTCONN'      | '0.197 IN' |'3521'  | 'http://speed.intel.com:8081/speed/module/pdm/item/pdm_item_detail_direct.asp?item_cde=H46321-001&item_rev=01&url_param=unused' | '' | '' | '' | '' | '' 
END_PART
END.
